# Artix - Datacenter Secure Control Module (DC-SCM) — KiCad project settings (.kicad_pro: net classes, design rules, text variables)
{
  "board": {
    "3dviewports": [],
    "design_settings": {
      "defaults": {
        "apply_defaults_to_fp_fields": false,
        "apply_defaults_to_fp_shapes": false,
        "apply_defaults_to_fp_text": false,
        "board_outline_line_width": 0.05,
        "copper_line_width": 0.2,
        "copper_text_italic": false,
        "copper_text_size_h": 1.5,
        "copper_text_size_v": 1.5,
        "copper_text_thickness": 0.3,
        "copper_text_upright": false,
        "courtyard_line_width": 0.05,
        "dimension_precision": 4,
        "dimension_units": 3,
        "dimensions": {
          "arrow_length": 1270000,
          "extension_offset": 500000,
          "keep_text_aligned": true,
          "suppress_zeroes": false,
          "text_position": 0,
          "units_format": 1
        },
        "fab_line_width": 0.1,
        "fab_text_italic": false,
        "fab_text_size_h": 1.0,
        "fab_text_size_v": 1.0,
        "fab_text_thickness": 0.15,
        "fab_text_upright": false,
        "other_line_width": 0.1,
        "other_text_italic": false,
        "other_text_size_h": 1.0,
        "other_text_size_v": 1.0,
        "other_text_thickness": 0.15,
        "other_text_upright": false,
        "pads": {
          "drill": 0.0,
          "height": 4.7,
          "width": 4.7
        },
        "silk_line_width": 0.12,
        "silk_text_italic": false,
        "silk_text_size_h": 0.7,
        "silk_text_size_v": 0.7,
        "silk_text_thickness": 0.15,
        "silk_text_upright": false,
        "zones": {
          "45_degree_only": false,
          "min_clearance": 0.15
        }
      },
      "diff_pair_dimensions": [
        {
          "gap": 0.0,
          "via_gap": 0.0,
          "width": 0.0
        }
      ],
      "drc_exclusions": [],
      "meta": {
        "filename": "board_design_settings.json",
        "version": 2
      },
      "rule_severities": {
        "annular_width": "error",
        "clearance": "error",
        "connection_width": "warning",
        "copper_edge_clearance": "error",
        "copper_sliver": "warning",
        "courtyards_overlap": "error",
        "creepage": "error",
        "diff_pair_gap_out_of_range": "error",
        "diff_pair_uncoupled_length_too_long": "error",
        "drill_out_of_range": "error",
        "duplicate_footprints": "warning",
        "extra_footprint": "warning",
        "footprint": "error",
        "footprint_filters_mismatch": "ignore",
        "footprint_symbol_mismatch": "warning",
        "footprint_type_mismatch": "ignore",
        "hole_clearance": "error",
        "hole_near_hole": "error",
        "hole_to_hole": "error",
        "holes_co_located": "warning",
        "invalid_outline": "error",
        "isolated_copper": "warning",
        "item_on_disabled_layer": "error",
        "items_not_allowed": "error",
        "length_out_of_range": "error",
        "lib_footprint_issues": "warning",
        "lib_footprint_mismatch": "warning",
        "malformed_courtyard": "error",
        "microvia_drill_out_of_range": "error",
        "mirrored_text_on_front_layer": "warning",
        "missing_courtyard": "warning",
        "missing_footprint": "warning",
        "net_conflict": "warning",
        "nonmirrored_text_on_back_layer": "warning",
        "npth_inside_courtyard": "ignore",
        "padstack": "error",
        "pth_inside_courtyard": "ignore",
        "shorting_items": "error",
        "silk_edge_clearance": "warning",
        "silk_over_copper": "warning",
        "silk_overlap": "warning",
        "skew_out_of_range": "error",
        "solder_mask_bridge": "error",
        "starved_thermal": "error",
        "text_height": "warning",
        "text_on_edge_cuts": "error",
        "text_thickness": "warning",
        "through_hole_pad_without_hole": "error",
        "too_many_vias": "error",
        "track_angle": "error",
        "track_dangling": "warning",
        "track_segment_length": "error",
        "track_width": "error",
        "tracks_crossing": "error",
        "unconnected_items": "error",
        "unresolved_variable": "error",
        "via_dangling": "warning",
        "zones_intersect": "error"
      },
      "rule_severitieslegacy_courtyards_overlap": true,
      "rule_severitieslegacy_no_courtyard_defined": false,
      "rules": {
        "allow_blind_buried_vias": true,
        "allow_microvias": false,
        "max_error": 0.005,
        "min_clearance": 0.0,
        "min_connection": 0.0,
        "min_copper_edge_clearance": 0.025,
        "min_groove_width": 0.0,
        "min_hole_clearance": 0.25,
        "min_hole_to_hole": 0.25,
        "min_microvia_diameter": 0.2,
        "min_microvia_drill": 0.1,
        "min_resolved_spokes": 2,
        "min_silk_clearance": 0.0,
        "min_text_height": 0.7,
        "min_text_thickness": 0.08,
        "min_through_hole_diameter": 0.15,
        "min_track_width": 0.1,
        "min_via_annular_width": 0.05,
        "min_via_diameter": 0.45,
        "solder_mask_to_copper_clearance": 0.0,
        "use_height_for_length_calcs": true
      },
      "teardrop_options": [
        {
          "td_onpthpad": true,
          "td_onroundshapesonly": false,
          "td_onsmdpad": true,
          "td_ontrackend": false,
          "td_onvia": true
        }
      ],
      "teardrop_parameters": [
        {
          "td_allow_use_two_tracks": true,
          "td_curve_segcount": 1,
          "td_height_ratio": 1.0,
          "td_length_ratio": 0.5,
          "td_maxheight": 2.0,
          "td_maxlen": 1.0,
          "td_on_pad_in_zone": false,
          "td_target_name": "td_round_shape",
          "td_width_to_size_filter_ratio": 0.9
        },
        {
          "td_allow_use_two_tracks": true,
          "td_curve_segcount": 1,
          "td_height_ratio": 1.0,
          "td_length_ratio": 0.5,
          "td_maxheight": 2.0,
          "td_maxlen": 1.0,
          "td_on_pad_in_zone": false,
          "td_target_name": "td_rect_shape",
          "td_width_to_size_filter_ratio": 0.9
        },
        {
          "td_allow_use_two_tracks": true,
          "td_curve_segcount": 1,
          "td_height_ratio": 1.0,
          "td_length_ratio": 0.5,
          "td_maxheight": 2.0,
          "td_maxlen": 1.0,
          "td_on_pad_in_zone": false,
          "td_target_name": "td_track_end",
          "td_width_to_size_filter_ratio": 0.9
        }
      ],
      "track_widths": [
        0.0,
        0.15,
        0.2,
        0.5
      ],
      "tuning_pattern_settings": {
        "diff_pair_defaults": {
          "corner_radius_percentage": 80,
          "corner_style": 1,
          "max_amplitude": 1.0,
          "min_amplitude": 0.2,
          "single_sided": false,
          "spacing": 1.0
        },
        "diff_pair_skew_defaults": {
          "corner_radius_percentage": 80,
          "corner_style": 1,
          "max_amplitude": 1.0,
          "min_amplitude": 0.2,
          "single_sided": false,
          "spacing": 0.6
        },
        "single_track_defaults": {
          "corner_radius_percentage": 80,
          "corner_style": 1,
          "max_amplitude": 1.0,
          "min_amplitude": 0.2,
          "single_sided": false,
          "spacing": 0.6
        }
      },
      "via_dimensions": [
        {
          "diameter": 0.0,
          "drill": 0.0
        }
      ],
      "zones_allow_external_fillets": false,
      "zones_use_no_outline": true
    },
    "ipc2581": {
      "dist": "",
      "distpn": "",
      "internal_id": "",
      "mfg": "",
      "mpn": ""
    },
    "layer_pairs": [],
    "layer_presets": [],
    "viewports": []
  },
  "boards": [],
  "cvpcb": {
    "equivalence_files": []
  },
  "erc": {
    "erc_exclusions": [],
    "meta": {
      "version": 0
    },
    "pin_map": [
      [
        0,
        0,
        0,
        0,
        0,
        0,
        1,
        0,
        0,
        0,
        0,
        2
      ],
      [
        0,
        2,
        0,
        1,
        0,
        0,
        1,
        0,
        2,
        2,
        2,
        2
      ],
      [
        0,
        0,
        0,
        0,
        0,
        0,
        1,
        0,
        1,
        0,
        1,
        2
      ],
      [
        0,
        1,
        0,
        0,
        0,
        0,
        1,
        1,
        2,
        1,
        1,
        2
      ],
      [
        0,
        0,
        0,
        0,
        0,
        0,
        1,
        0,
        0,
        0,
        0,
        2
      ],
      [
        0,
        0,
        0,
        0,
        0,
        0,
        0,
        0,
        0,
        0,
        0,
        2
      ],
      [
        1,
        1,
        1,
        1,
        1,
        0,
        1,
        1,
        1,
        1,
        1,
        2
      ],
      [
        0,
        0,
        0,
        1,
        0,
        0,
        1,
        0,
        0,
        0,
        0,
        2
      ],
      [
        0,
        2,
        1,
        2,
        0,
        0,
        1,
        0,
        2,
        2,
        2,
        2
      ],
      [
        0,
        2,
        0,
        1,
        0,
        0,
        1,
        0,
        2,
        0,
        0,
        2
      ],
      [
        0,
        2,
        1,
        1,
        0,
        0,
        1,
        0,
        2,
        0,
        0,
        2
      ],
      [
        2,
        2,
        2,
        2,
        2,
        2,
        2,
        2,
        2,
        2,
        2,
        2
      ]
    ],
    "rule_severities": {
      "bus_definition_conflict": "error",
      "bus_entry_needed": "error",
      "bus_to_bus_conflict": "error",
      "bus_to_net_conflict": "error",
      "conflicting_netclasses": "error",
      "different_unit_footprint": "error",
      "different_unit_net": "error",
      "duplicate_reference": "error",
      "duplicate_sheet_names": "error",
      "endpoint_off_grid": "warning",
      "extra_units": "error",
      "footprint_filter": "ignore",
      "footprint_link_issues": "warning",
      "four_way_junction": "ignore",
      "global_label_dangling": "warning",
      "hier_label_mismatch": "error",
      "label_dangling": "error",
      "label_multiple_wires": "warning",
      "lib_symbol_issues": "warning",
      "lib_symbol_mismatch": "warning",
      "missing_bidi_pin": "warning",
      "missing_input_pin": "warning",
      "missing_power_pin": "error",
      "missing_unit": "warning",
      "multiple_net_names": "warning",
      "net_not_bus_member": "warning",
      "no_connect_connected": "warning",
      "no_connect_dangling": "warning",
      "pin_not_connected": "error",
      "pin_not_driven": "error",
      "pin_to_pin": "error",
      "power_pin_not_driven": "error",
      "same_local_global_label": "warning",
      "similar_label_and_power": "warning",
      "similar_labels": "warning",
      "similar_power": "warning",
      "simulation_model_issue": "ignore",
      "single_global_label": "ignore",
      "unannotated": "error",
      "unconnected_wire_endpoint": "warning",
      "undefined_netclass": "error",
      "unit_value_mismatch": "error",
      "unresolved_variable": "error",
      "wire_dangling": "error"
    }
  },
  "libraries": {
    "pinned_footprint_libs": [],
    "pinned_symbol_libs": []
  },
  "meta": {
    "filename": "artix-dc-scm.kicad_pro",
    "version": 3
  },
  "net_settings": {
    "classes": [
      {
        "bus_width": 12,
        "clearance": 0.1,
        "diff_pair_gap": 0.2,
        "diff_pair_via_gap": 0.25,
        "diff_pair_width": 0.1,
        "line_style": 0,
        "microvia_diameter": 0.3,
        "microvia_drill": 0.1,
        "name": "Default",
        "pcb_color": "rgba(0, 0, 0, 0.000)",
        "priority": 2147483647,
        "schematic_color": "rgba(0, 0, 0, 0.000)",
        "track_width": 0.1,
        "via_diameter": 0.5,
        "via_drill": 0.2,
        "wire_width": 6
      },
      {
        "bus_width": 12,
        "clearance": 0.1,
        "diff_pair_gap": 0.11,
        "diff_pair_via_gap": 0.25,
        "diff_pair_width": 0.11,
        "line_style": 0,
        "microvia_diameter": 0.5,
        "microvia_drill": 0.1,
        "name": "Ethernet",
        "pcb_color": "rgba(0, 0, 0, 0.000)",
        "priority": 0,
        "schematic_color": "rgba(0, 0, 0, 0.000)",
        "track_width": 0.11,
        "via_diameter": 0.5,
        "via_drill": 0.2,
        "wire_width": 6
      },
      {
        "bus_width": 12,
        "clearance": 0.1,
        "diff_pair_gap": 0.1,
        "diff_pair_via_gap": 0.25,
        "diff_pair_width": 0.15,
        "line_style": 0,
        "microvia_diameter": 0.5,
        "microvia_drill": 0.2,
        "name": "PCIe",
        "pcb_color": "rgba(0, 0, 0, 0.000)",
        "priority": 1,
        "schematic_color": "rgba(0, 0, 0, 0.000)",
        "track_width": 0.11,
        "via_diameter": 0.5,
        "via_drill": 0.2,
        "wire_width": 6
      },
      {
        "bus_width": 12,
        "clearance": 0.15,
        "diff_pair_gap": 0.21,
        "diff_pair_via_gap": 0.25,
        "diff_pair_width": 0.11,
        "line_style": 0,
        "microvia_diameter": 0.3,
        "microvia_drill": 0.1,
        "name": "PCIe_inner",
        "pcb_color": "rgba(0, 0, 0, 0.000)",
        "priority": 2,
        "schematic_color": "rgba(0, 0, 0, 0.000)",
        "track_width": 0.11,
        "via_diameter": 0.5,
        "via_drill": 0.2,
        "wire_width": 6
      },
      {
        "bus_width": 12,
        "clearance": 0.15,
        "diff_pair_gap": 0.15,
        "diff_pair_via_gap": 0.25,
        "diff_pair_width": 0.16,
        "line_style": 0,
        "microvia_diameter": 0.3,
        "microvia_drill": 0.1,
        "name": "USB",
        "pcb_color": "rgba(0, 0, 0, 0.000)",
        "priority": 3,
        "schematic_color": "rgba(0, 0, 0, 0.000)",
        "track_width": 0.16,
        "via_diameter": 0.5,
        "via_drill": 0.2,
        "wire_width": 6
      }
    ],
    "meta": {
      "version": 4
    },
    "net_colors": null,
    "netclass_assignments": null,
    "netclass_patterns": [
      {
        "netclass": "Ethernet",
        "pattern": "/Ethernet/ETH1_N"
      },
      {
        "netclass": "Ethernet",
        "pattern": "/Ethernet/ETH1_P"
      },
      {
        "netclass": "Ethernet",
        "pattern": "/Ethernet/ETH2_N"
      },
      {
        "netclass": "Ethernet",
        "pattern": "/Ethernet/ETH2_P"
      },
      {
        "netclass": "Ethernet",
        "pattern": "/Ethernet/ETH3_N"
      },
      {
        "netclass": "Ethernet",
        "pattern": "/Ethernet/ETH3_P"
      },
      {
        "netclass": "Ethernet",
        "pattern": "/Ethernet/ETH4_N"
      },
      {
        "netclass": "Ethernet",
        "pattern": "/Ethernet/ETH4_P"
      },
      {
        "netclass": "PCIe",
        "pattern": "/Interfaces/PCIE_BMC_TX_C_N"
      },
      {
        "netclass": "PCIe",
        "pattern": "/Interfaces/PCIE_BMC_TX_C_P"
      },
      {
        "netclass": "PCIe",
        "pattern": "/PCIe-connector/PCIE_HPM_TX0_C_N"
      },
      {
        "netclass": "PCIe",
        "pattern": "/PCIe-connector/PCIE_HPM_TX0_C_P"
      },
      {
        "netclass": "PCIe",
        "pattern": "/PCIe-connector/PCIE_HPM_TX1_C_N"
      },
      {
        "netclass": "PCIe",
        "pattern": "/PCIe-connector/PCIE_HPM_TX1_C_P"
      },
      {
        "netclass": "PCIe",
        "pattern": "/PCIe-connector/PCIE_HPM_TX2_C_N"
      },
      {
        "netclass": "PCIe",
        "pattern": "/PCIe-connector/PCIE_HPM_TX2_C_P"
      },
      {
        "netclass": "PCIe",
        "pattern": "/PCIe-connector/PCIE_HPM_TX3_C_N"
      },
      {
        "netclass": "PCIe",
        "pattern": "/PCIe-connector/PCIE_HPM_TX3_C_P"
      },
      {
        "netclass": "PCIe",
        "pattern": "PCIE_BMC_CLK_100_N"
      },
      {
        "netclass": "PCIe",
        "pattern": "PCIE_BMC_CLK_100_P"
      },
      {
        "netclass": "PCIe",
        "pattern": "PCIE_BMC_RX_N"
      },
      {
        "netclass": "PCIe",
        "pattern": "PCIE_BMC_RX_P"
      },
      {
        "netclass": "PCIe",
        "pattern": "PCIE_BMC_TX_N"
      },
      {
        "netclass": "PCIe",
        "pattern": "PCIE_BMC_TX_P"
      },
      {
        "netclass": "PCIe",
        "pattern": "PCIE_HPM_CLK_N"
      },
      {
        "netclass": "PCIe",
        "pattern": "PCIE_HPM_CLK_P"
      },
      {
        "netclass": "PCIe",
        "pattern": "PCIE_HPM_RX[0]_N"
      },
      {
        "netclass": "PCIe",
        "pattern": "PCIE_HPM_RX[0]_P"
      },
      {
        "netclass": "PCIe",
        "pattern": "PCIE_HPM_RX[1]_N"
      },
      {
        "netclass": "PCIe",
        "pattern": "PCIE_HPM_RX[1]_P"
      },
      {
        "netclass": "PCIe",
        "pattern": "PCIE_HPM_RX[2]_N"
      },
      {
        "netclass": "PCIe",
        "pattern": "PCIE_HPM_RX[2]_P"
      },
      {
        "netclass": "PCIe",
        "pattern": "PCIE_HPM_RX[3]_N"
      },
      {
        "netclass": "PCIe",
        "pattern": "PCIE_HPM_RX[3]_P"
      },
      {
        "netclass": "PCIe",
        "pattern": "PCIE_HPM_TX[0]_N"
      },
      {
        "netclass": "PCIe",
        "pattern": "PCIE_HPM_TX[0]_P"
      },
      {
        "netclass": "PCIe",
        "pattern": "PCIE_HPM_TX[1]_N"
      },
      {
        "netclass": "PCIe",
        "pattern": "PCIE_HPM_TX[1]_P"
      },
      {
        "netclass": "PCIe",
        "pattern": "PCIE_HPM_TX[2]_N"
      },
      {
        "netclass": "PCIe",
        "pattern": "PCIE_HPM_TX[2]_P"
      },
      {
        "netclass": "PCIe",
        "pattern": "PCIE_HPM_TX[3]_N"
      },
      {
        "netclass": "PCIe",
        "pattern": "PCIE_HPM_TX[3]_P"
      },
      {
        "netclass": "USB",
        "pattern": "USB1_D_N"
      },
      {
        "netclass": "USB",
        "pattern": "USB1_D_P"
      },
      {
        "netclass": "USB",
        "pattern": "USB2_D_N"
      },
      {
        "netclass": "USB",
        "pattern": "USB2_D_P"
      }
    ]
  },
  "pcbnew": {
    "last_paths": {
      "gencad": "",
      "idf": "",
      "netlist": "",
      "plot": "",
      "pos_files": "",
      "specctra_dsn": "",
      "step": "",
      "svg": "",
      "vrml": ""
    },
    "page_layout_descr_file": ""
  },
  "schematic": {
    "annotate_start_num": 0,
    "bom_export_filename": "${PROJECTNAME}.csv",
    "bom_fmt_presets": [],
    "bom_fmt_settings": {
      "field_delimiter": ",",
      "keep_line_breaks": false,
      "keep_tabs": false,
      "name": "CSV",
      "ref_delimiter": ",",
      "ref_range_delimiter": "",
      "string_delimiter": "\""
    },
    "bom_presets": [],
    "bom_settings": {
      "exclude_dnp": false,
      "fields_ordered": [
        {
          "group_by": false,
          "label": "Reference",
          "name": "Reference",
          "show": true
        },
        {
          "group_by": false,
          "label": "Qty",
          "name": "${QUANTITY}",
          "show": true
        },
        {
          "group_by": true,
          "label": "Value",
          "name": "Value",
          "show": true
        },
        {
          "group_by": true,
          "label": "DNP",
          "name": "${DNP}",
          "show": true
        },
        {
          "group_by": true,
          "label": "Exclude from BOM",
          "name": "${EXCLUDE_FROM_BOM}",
          "show": true
        },
        {
          "group_by": true,
          "label": "Exclude from Board",
          "name": "${EXCLUDE_FROM_BOARD}",
          "show": true
        },
        {
          "group_by": true,
          "label": "Footprint",
          "name": "Footprint",
          "show": true
        },
        {
          "group_by": false,
          "label": "Datasheet",
          "name": "Datasheet",
          "show": true
        }
      ],
      "filter_string": "",
      "group_symbols": true,
      "include_excluded_from_bom": true,
      "name": "Default Editing",
      "sort_asc": true,
      "sort_field": "Reference"
    },
    "connection_grid_size": 50.0,
    "drawing": {
      "dashed_lines_dash_length_ratio": 12.0,
      "dashed_lines_gap_length_ratio": 3.0,
      "default_line_thickness": 6.0,
      "default_text_size": 50.0,
      "field_names": [],
      "intersheets_ref_own_page": false,
      "intersheets_ref_prefix": "",
      "intersheets_ref_short": false,
      "intersheets_ref_show": false,
      "intersheets_ref_suffix": "",
      "junction_size_choice": 3,
      "label_size_ratio": 0.25,
      "operating_point_overlay_i_precision": 3,
      "operating_point_overlay_i_range": "~A",
      "operating_point_overlay_v_precision": 3,
      "operating_point_overlay_v_range": "~V",
      "overbar_offset_ratio": 1.23,
      "pin_symbol_size": 0.0,
      "text_offset_ratio": 0.08
    },
    "legacy_lib_dir": "",
    "legacy_lib_list": [],
    "meta": {
      "version": 1
    },
    "net_format_name": "",
    "ngspice": {
      "fix_include_paths": true,
      "fix_passive_vals": false,
      "meta": {
        "version": 0
      },
      "model_mode": 0,
      "workbook_filename": ""
    },
    "page_layout_descr_file": "",
    "plot_directory": "./doc/",
    "space_save_all_events": true,
    "spice_adjust_passive_values": false,
    "spice_current_sheet_as_root": false,
    "spice_external_command": "spice \"%I\"",
    "spice_model_current_sheet_as_root": true,
    "spice_save_all_currents": false,
    "spice_save_all_dissipations": false,
    "spice_save_all_voltages": false,
    "subpart_first_id": 65,
    "subpart_id_separator": 0
  },
  "sheets": [
    [
      "",
      "Root"
    ],
    [
      "",
      "Ethernet"
    ],
    [
      "",
      "FPGA power supply"
    ],
    [
      "",
      "PCIe-connector"
    ],
    [
      "",
      "FPGA banks 13-16"
    ],
    [
      "",
      "RoT"
    ],
    [
      "",
      "Edge connector"
    ],
    [
      "",
      "Interfaces"
    ],
    [
      "",
      "DDR3"
    ],
    [
      "",
      "Power supply"
    ],
    [
      "",
      "FPGA banks 34-35 & CFG"
    ]
  ],
  "text_variables": {}
}
